# S9S_MB_2U (Grand Teton) — schematic netlist excerpt (pin names and nets, part order shuffled) for the footprints in the layout excerpt that follows; sources: Cadence DE-HDL packaged netlist, KiCad conversion of 03242023_DA0F0TMBIJ0_F0T_Motherboard_J_brd_V01_OCP.brd

PU7_P0_7  ISL99390FRZTR5935  ISL99390FRZ-TR5935 IC  pkg QFN21_6X5XB  page 270
  VOS  = PVCCIN_CPU0_VOS7
  AGND  = GND
  VCC  = PVCCIN_CPU0_VDD7
  PVCC  = PVCCIN_CPU0_PVCC
  PGND1  = GND
  GL1  = NC
  PGND2  = GND
  SW  = SW_PVCCIN_CPU0_SW7
  VIN1  = SW_P12V_PVCCIN_CPU0_FLT
  VIN2  = SW_P12V_PVCCIN_CPU0_FLT
  DNC  = NC
  PHASE  = SW_PVCCIN_CPU0_BOOTR7
  BOOT  = SW_PVCCIN_CPU0_BOOT7
  PWM  = PVCCIN_CPU0_PWM7
  EN  = PVCCIN_CPU0_VDD7
  TOUT_FLT  = PVCCIN_CPU0_ATSEN
  LSET  = PVCCIN_CPU0_LSET7
  IOUT  = PVCCIN_CPU0_IMON7
  REFIN  = PVCCIN_CPU0_VREF
  PGND3  = GND
  GL2  = NC

(kicad_pcb
	(version 20260206)
	(generator "pcbnew")
	(generator_version "10.0")
	(general
		(thickness 1.6)
		(legacy_teardrops no)
	)
	(paper "A4")
	(title_block
		(title "03242023_DA0F0TMBIJ0_F0T_Motherboard_J_brd_V01_OCP.brd")
		(comment 1 "Grand Teton / footprints 3699-3699 of 6105")
	)
	(layers
		(0 "F.Cu" signal "TOP")
		(4 "In1.Cu" signal "GND")
		(6 "In2.Cu" signal "IN1")
		(8 "In3.Cu" signal "GND1")
		(10 "In4.Cu" signal "IN2")
		(12 "In5.Cu" signal "GND2")
		(14 "In6.Cu" signal "IN3")
		(16 "In7.Cu" signal "GND3")
		(18 "In8.Cu" signal "VCC")
		(20 "In9.Cu" signal "VCC1")
		(22 "In10.Cu" signal "GND4")
		(24 "In11.Cu" signal "IN4")
		(26 "In12.Cu" signal "GND5")
		(28 "In13.Cu" signal "IN5")
		(30 "In14.Cu" signal "GND6")
		(32 "In15.Cu" signal "IN6")
		(34 "In16.Cu" signal "GND7")
		(2 "B.Cu" signal "BOTTOM")
		(9 "F.Adhes" user "F.Adhesive")
		(11 "B.Adhes" user "B.Adhesive")
		(13 "F.Paste" user "Package Geometry/Pastemask Top")
		(15 "B.Paste" user "Package Geometry/Pastemask Bottom")
		(5 "F.SilkS" user "Ref Des/Silkscreen Top")
		(7 "B.SilkS" user "Ref Des/Silkscreen Bottom")
		(1 "F.Mask" user "Board Geometry/Soldermask Top")
		(3 "B.Mask" user "Board Geometry/Soldermask Bottom")
		(17 "Dwgs.User" user "User.Drawings")
		(19 "Cmts.User" user "User.Comments")
		(21 "Eco1.User" user "User.Eco1")
		(23 "Eco2.User" user "User.Eco2")
		(25 "Edge.Cuts" user "Board Geometry/Outline")
		(27 "Margin" user)
		(31 "F.CrtYd" user "Package Geometry/Place Bound Top")
		(29 "B.CrtYd" user "Package Geometry/Place Bound Bottom")
		(35 "F.Fab" user "Ref Des/Assembly Top")
		(33 "B.Fab" user "Ref Des/Assembly Bottom")
	)
	(footprint ""
		(layer "F.Cu")
		(at 328.647044 -342.976962)
		(property "Reference" "PU7_P0_7"
			(at -10.682224 -1.070356 0)
			(unlocked yes)
			(layer "F.SilkS")
			(effects
				(font
					(size 0.7874 0.5842)
					(thickness 0.1524)
				)
				(justify left)
			)
		)
		(property "Value" ""
			(at 0 0 0)
			(layer "F.Fab")
			(effects
				(font
					(size 1.27 1.27)
				)
			)
		)
		(duplicate_pad_numbers_are_jumpers no)
		(fp_line
			(start -2.500122 -2.999994)
			(end -2.24409 -2.999994)
			(stroke
				(width 0.1524)
				(type default)
			)
			(layer "F.SilkS")
		)
		(fp_line
			(start -2.500122 -2.529078)
			(end -2.500122 -2.999994)
			(stroke
				(width 0.1524)
				(type default)
			)
			(layer "F.SilkS")
		)
		(fp_line
			(start -2.500122 0.6604)
			(end -2.500122 0.229108)
			(stroke
				(width 0.1524)
				(type default)
			)
			(layer "F.SilkS")
		)
		(fp_line
			(start -2.500122 2.999994)
			(end -2.500122 2.339594)
			(stroke
				(width 0.1524)
				(type default)
			)
			(layer "F.SilkS")
		)
		(fp_line
			(start -2.2987 2.999994)
			(end -2.500122 2.999994)
			(stroke
				(width 0.1524)
				(type default)
			)
			(layer "F.SilkS")
		)
		(fp_line
			(start 2.31394 -2.999994)
			(end 2.500122 -2.999994)
			(stroke
				(width 0.1524)
				(type default)
			)
			(layer "F.SilkS")
		)
		(fp_line
			(start 2.500122 -2.999994)
			(end 2.500122 -2.44348)
			(stroke
				(width 0.1524)
				(type default)
			)
			(layer "F.SilkS")
		)
		(fp_line
			(start 2.500122 2.339594)
			(end 2.500122 2.999994)
			(stroke
				(width 0.1524)
				(type default)
			)
			(layer "F.SilkS")
		)
		(fp_line
			(start 2.500122 2.999994)
			(end 2.2987 2.999994)
			(stroke
				(width 0.1524)
				(type default)
			)
			(layer "F.SilkS")
		)
		(fp_poly
			(pts
				(xy -2.176272 -3.637534) (xy -2.684272 -2.621534) (xy -3.192272 -3.637534)
			)
			(stroke
				(width 0)
				(type default)
			)
			(fill yes)
			(layer "F.SilkS")
		)
		(fp_line
			(start -2.500122 -2.999994)
			(end 2.500122 -2.999994)
			(stroke
				(width 0.1)
				(type default)
			)
			(layer "F.Fab")
		)
		(fp_line
			(start -2.500122 2.999994)
			(end -2.500122 -2.999994)
			(stroke
				(width 0.1)
				(type default)
			)
			(layer "F.Fab")
		)
		(fp_line
			(start 2.500122 -2.999994)
			(end 2.500122 2.999994)
			(stroke
				(width 0.1)
				(type default)
			)
			(layer "F.Fab")
		)
		(fp_line
			(start 2.500122 2.999994)
			(end -2.500122 2.999994)
			(stroke
				(width 0.1)
				(type default)
			)
			(layer "F.Fab")
		)
		(fp_poly
			(pts
				(xy -4.218432 -2.783078) (xy -4.218432 -1.767078) (xy -3.202432 -2.275078)
			)
			(stroke
				(width 0)
				(type default)
			)
			(fill yes)
			(layer "F.Fab")
		)
		(pad "1" smd rect
			(at -2.400046 -2.275078 90)
			(size 0.2286 0.6096)
			(layers "F.Cu" "F.Mask" "F.Paste")
			(net "PVCCIN_CPU0_VOS7")
		)
		(pad "2" smd rect
			(at -2.400046 -1.82499 90)
			(size 0.2286 0.6096)
			(layers "F.Cu" "F.Mask" "F.Paste")
			(net "GND")
		)
		(pad "3" smd rect
			(at -2.400046 -1.374902 90)
			(size 0.2286 0.6096)
			(layers "F.Cu" "F.Mask" "F.Paste")
			(net "PVCCIN_CPU0_VDD7")
		)
		(pad "4" smd rect
			(at -2.400046 -0.925068 90)
			(size 0.2286 0.6096)
			(layers "F.Cu" "F.Mask" "F.Paste")
			(net "PVCCIN_CPU0_PVCC")
		)
		(pad "5" smd rect
			(at -2.400046 -0.47498 90)
			(size 0.2286 0.6096)
			(layers "F.Cu" "F.Mask" "F.Paste")
			(net "GND")
		)
		(pad "6" smd rect
			(at -2.400046 -0.024892 90)
			(size 0.2286 0.6096)
			(layers "F.Cu" "F.Mask" "F.Paste")
			(net "Net_8562")
		)
		(pad "7_9-20_24" smd circle
			(at 0 1.150112 90)
			(size 0 0)
			(layers "F.Cu" "F.Mask" "F.Paste")
			(net "GND")
		)
		(pad "10_19" smd rect
			(at 0 2.899918 90)
			(size 0.6096 4.318)
			(layers "F.Cu" "F.Mask" "F.Paste")
			(net "SW_PVCCIN_CPU0_SW7")
		)
		(pad "25_29" smd rect
			(at 1.549908 -1.279906 270)
			(size 2.0574 2.3114)
			(layers "F.Cu" "F.Mask" "F.Paste")
			(net "SW_P12V_PVCCIN_CPU0_FLT")
		)
		(pad "30" smd rect
			(at 2.05994 -2.899918)
			(size 0.2286 0.6096)
			(layers "F.Cu" "F.Mask" "F.Paste")
			(net "SW_P12V_PVCCIN_CPU0_FLT")
		)
		(pad "31" smd rect
			(at 1.610106 -2.899918)
			(size 0.2286 0.6096)
			(layers "F.Cu" "F.Mask" "F.Paste")
			(net "Net_8563")
		)
		(pad "32" smd rect
			(at 1.160018 -2.899918)
			(size 0.2286 0.6096)
			(layers "F.Cu" "F.Mask" "F.Paste")
			(net "SW_PVCCIN_CPU0_BOOTR7")
		)
		(pad "33" smd rect
			(at 0.70993 -2.899918)
			(size 0.2286 0.6096)
			(layers "F.Cu" "F.Mask" "F.Paste")
			(net "SW_PVCCIN_CPU0_BOOT7")
		)
		(pad "34" smd rect
			(at 0.260096 -2.899918)
			(size 0.2286 0.6096)
			(layers "F.Cu" "F.Mask" "F.Paste")
			(net "PVCCIN_CPU0_PWM7")
		)
		(pad "35" smd rect
			(at -0.189992 -2.899918)
			(size 0.2286 0.6096)
			(layers "F.Cu" "F.Mask" "F.Paste")
			(net "PVCCIN_CPU0_VDD7")
		)
		(pad "36" smd rect
			(at -0.64008 -2.899918)
			(size 0.2286 0.6096)
			(layers "F.Cu" "F.Mask" "F.Paste")
			(net "PVCCIN_CPU0_ATSEN")
		)
		(pad "37" smd rect
			(at -1.089914 -2.899918)
			(size 0.2286 0.6096)
			(layers "F.Cu" "F.Mask" "F.Paste")
			(net "PVCCIN_CPU0_LSET7")
		)
		(pad "38" smd rect
			(at -1.540002 -2.899918)
			(size 0.2286 0.6096)
			(layers "F.Cu" "F.Mask" "F.Paste")
			(net "PVCCIN_CPU0_IMON7")
		)
		(pad "39" smd rect
			(at -1.99009 -2.899918)
			(size 0.2286 0.6096)
			(layers "F.Cu" "F.Mask" "F.Paste")
			(net "PVCCIN_CPU0_VREF")
		)
		(pad "40" smd rect
			(at -0.87503 -1.27508)
			(size 1.7526 1.9558)
			(layers "F.Cu" "F.Mask" "F.Paste")
			(net "GND")
		)
		(pad "41" smd rect
			(at -1.525016 0.249936 270)
			(size 0.3048 0.4572)
			(layers "F.Cu" "F.Mask" "F.Paste")
			(net "Net_8561")
		)
		(zone
			(layer "F.Cu")
			(hatch none 0.5)
			(connect_pads
				(clearance 0)
			)
			(min_thickness 0.25)
			(keepout
				(tracks not_allowed)
				(vias allowed)
				(pads allowed)
				(copperpour not_allowed)
				(footprints allowed)
			)
			(placement
				(enabled no)
				(sheetname "")
			)
			(fill
				(thermal_gap 0.5)
				(thermal_bridge_width 0.5)
				(island_removal_mode 0)
			)
			(polygon
				(pts
					(xy 326.602598 -344.658188) (xy 326.844914 -344.658188) (xy 326.844914 -343.624408) (xy 326.602598 -343.624408)
				)
			)
		)
		(zone
			(layer "F.Cu")
			(hatch none 0.5)
			(connect_pads
				(clearance 0)
			)
			(min_thickness 0.25)
			(keepout
				(tracks not_allowed)
				(vias allowed)
				(pads allowed)
				(copperpour not_allowed)
				(footprints allowed)
			)
			(placement
				(enabled no)
				(sheetname "")
			)
			(fill
				(thermal_gap 0.5)
				(thermal_bridge_width 0.5)
				(island_removal_mode 0)
			)
			(polygon
				(pts
					(xy 326.146922 -339.976968) (xy 326.146922 -340.655148) (xy 331.10678 -340.655148) (xy 331.10678 -339.976968)
					(xy 330.856844 -339.976968) (xy 330.856844 -340.432644) (xy 326.437244 -340.432644) (xy 326.437244 -339.976968)
				)
			)
		)
	)
)
